G04 ================== begin FILE IDENTIFICATION RECORD ==================*
G04 Layout Name:  16368-sb.brd*
G04 Film Name:    L5GND*
G04 File Format:  Gerber RS274X*
G04 File Origin:  Cadence Allegro 16.5-S056*
G04 Origin Date:  Tue Feb 07 09:07:44 2017*
G04 *
G04 Layer:  VIA CLASS/L5GND*
G04 Layer:  PIN/L5GND*
G04 Layer:  ETCH/L5GND*
G04 Layer:  DRAWING FORMAT/LAYER_PCB_STORY*
G04 Layer:  DRAWING FORMAT/LAYER_L5GND*
G04 *
G04 Offset:    (0.00 0.00)*
G04 Mirror:    No*
G04 Mode:      Negative*
G04 Rotation:  0*
G04 FullContactRelief:  No*
G04 UndefLineWidth:     6.00*
G04 ================== end FILE IDENTIFICATION RECORD ====================*
%FSLAX35Y35*MOIN*%
%IR0*IPPOS*OFA0.00000B0.00000*MIA0B0*SFA1.00000B1.00000*%
%ADD15C,.03*%
%ADD13C,.054*%
%ADD16C,.068*%
%AMMACRO11*
4,1,15,.00398,.00044,
.003999,.000208,
.004004,-.000025,
.003996,-.000258,
.00398,-.00044,
.00483,-.00129,
.004897,-.001007,
.004947,-.000721,
.004981,-.000432,
.004997,-.000141,
.004997,.000149,
.00498,.00044,
.004946,.000729,
.004895,.001015,
.00483,.00129,
.00398,.00044,
0.0*
4,1,15,.00044,-.00398,
.000208,-.003999,
-.000025,-.004004,
-.000258,-.003996,
-.00044,-.00398,
-.00129,-.00483,
-.001007,-.004897,
-.000721,-.004947,
-.000432,-.004981,
-.000141,-.004997,
.000149,-.004997,
.00044,-.00498,
.000729,-.004946,
.001015,-.004895,
.00129,-.00483,
.00044,-.00398,
0.0*
4,1,15,-.00398,-.00044,
-.003999,-.000208,
-.004004,.000025,
-.003996,.000258,
-.00398,.00044,
-.00483,.00129,
-.004897,.001007,
-.004947,.000721,
-.004981,.000432,
-.004997,.000141,
-.004997,-.000149,
-.00498,-.00044,
-.004946,-.000729,
-.004895,-.001015,
-.00483,-.00129,
-.00398,-.00044,
0.0*
4,1,15,-.00044,.00398,
-.000208,.003999,
.000025,.004004,
.000258,.003996,
.00044,.00398,
.00129,.00483,
.001007,.004897,
.000721,.004947,
.000432,.004981,
.000141,.004997,
-.000149,.004997,
-.00044,.00498,
-.000729,.004946,
-.001015,.004895,
-.00129,.00483,
-.00044,.00398,
0.0*
%
%ADD11MACRO11*%
%ADD12C,.114*%
%ADD17O,.068X.051*%
%ADD10C,.225*%
%AMMACRO14*
4,1,19,.02172,.00757,
.022123,.006294,
.022452,.004997,
.022705,.003683,
.02288,.002357,
.022979,.001023,
.022999,-.000315,
.022942,-.001652,
.022807,-.002983,
.022595,-.004304,
.022307,-.005611,
.021943,-.006898,
.02172,-.00757,
.02556,-.01142,
.027155,-.006808,
.027924,-.001989,
.027846,.00289,
.026921,.007681,
.02556,.01142,
.02172,.00757,
0.0*
4,1,19,.00757,-.02172,
.006294,-.022123,
.004997,-.022452,
.003683,-.022705,
.002357,-.02288,
.001023,-.022979,
-.000315,-.022999,
-.001652,-.022942,
-.002983,-.022807,
-.004304,-.022595,
-.005611,-.022307,
-.006898,-.021943,
-.00757,-.02172,
-.01142,-.02556,
-.006808,-.027155,
-.001989,-.027924,
.00289,-.027846,
.007681,-.026921,
.01142,-.02556,
.00757,-.02172,
0.0*
4,1,19,-.02172,-.00757,
-.022123,-.006294,
-.022452,-.004997,
-.022705,-.003683,
-.02288,-.002357,
-.022979,-.001023,
-.022999,.000315,
-.022942,.001652,
-.022807,.002983,
-.022595,.004304,
-.022307,.005611,
-.021943,.006898,
-.02172,.00757,
-.02556,.01142,
-.027155,.006808,
-.027924,.001989,
-.027846,-.00289,
-.026921,-.007681,
-.02556,-.01142,
-.02172,-.00757,
0.0*
4,1,19,-.00757,.02172,
-.006294,.022123,
-.004997,.022452,
-.003683,.022705,
-.002357,.02288,
-.001023,.022979,
.000315,.022999,
.001652,.022942,
.002983,.022807,
.004304,.022595,
.005611,.022307,
.006898,.021943,
.00757,.02172,
.01142,.02556,
.006808,.027155,
.001989,.027924,
-.00289,.027846,
-.007681,.026921,
-.01142,.02556,
-.00757,.02172,
0.0*
%
%ADD14MACRO14*%
%ADD18C,.02*%
%ADD19C,.006*%
%ADD22C,.05004*%
%ADD24C,.06404*%
%ADD23C,.11004*%
%ADD21C,.20504*%
%ADD20O,.06402X.04702*%
G75*
%LPD*%
G75*
G36*
G01X-6000Y-6000D02*
X183165D01*
Y67811D01*
X-6000D01*
Y-6000D01*
G37*
%LPC*%
G75*
G36*
G01X174161Y3937D02*
G02X173228Y3004I-933J0D01*
G01X3937D01*
G02X3004Y3937I0J933D01*
G01Y57874D01*
G02X3937Y58807I933J0D01*
G01X173228D01*
G02X174161Y57874I0J-933D01*
G01Y3937D01*
G37*
%LPD*%
G75*
G54D22*
X26890Y46949D03*
G54D24*
X103642Y43898D03*
X127264D03*
G54D23*
X9000Y48000D03*
X164500Y48500D03*
G54D21*
X17717Y19685D03*
X159449D03*
G54D20*
X56418Y46949D03*
G54D15*
X28100Y39300D03*
X34200Y47000D03*
X28100Y55300D03*
X30827Y47067D03*
X109000Y11000D03*
X95400Y12500D03*
X84100Y14900D03*
X81500Y12700D03*
X74200Y21700D03*
X53437Y13900D03*
X71405Y19607D03*
X68500Y13800D03*
X98000Y25500D03*
X69000Y17200D03*
X84700Y26702D03*
X65300Y24437D03*
X65800Y21000D03*
X46000Y25600D03*
X54500Y25500D03*
X98700Y21000D03*
X95300D03*
X85100Y21100D03*
X56200Y21000D03*
X52800D03*
X45250Y35850D03*
X36733Y47067D03*
X111800Y52264D03*
X96000Y55600D03*
X44607Y46831D03*
X39400D03*
X111700Y39600D03*
X52218Y47067D03*
X56000Y55500D03*
X103700Y36400D03*
X39300Y35500D03*
X47200Y47067D03*
X49730Y46821D03*
X76000Y37750D03*
X87700Y43400D03*
X94800Y46800D03*
X93000Y49700D03*
X58000Y38500D03*
X74000Y34900D03*
X133500Y15700D03*
X118300Y19900D03*
X134200Y9000D03*
X131000Y6000D03*
X127500Y52264D03*
X119500Y33900D03*
X127500Y37000D03*
G54D13*
X26890Y46949D03*
G54D16*
X103642Y43898D03*
X127264D03*
G54D11*
X28802Y13285D03*
X24117Y8600D03*
X11317D03*
X6632Y13285D03*
Y26085D03*
X11317Y30770D03*
X24117D03*
X28802Y26085D03*
X20000Y55000D03*
X15000Y45000D03*
X5000Y38000D03*
Y55000D03*
X68750Y24100D03*
X79940Y26850D03*
X70700Y11200D03*
X40100Y21692D03*
X35000Y5000D03*
X41200Y7400D03*
X98200Y16500D03*
X108140Y28132D03*
X87900Y53100D03*
X103655Y52264D03*
X61300Y47250D03*
X88940Y39400D03*
X170534Y13285D03*
X165849Y8600D03*
X153049D03*
X148364Y13285D03*
Y26085D03*
X153049Y30770D03*
X165849D03*
X170534Y26085D03*
X119400Y29800D03*
X143000Y5000D03*
X137000Y12750D03*
X170000Y45000D03*
X135500D03*
X155000D03*
X165000Y55000D03*
X145000D03*
Y36500D03*
X119403Y52264D03*
G54D12*
X9000Y48000D03*
X164500Y48500D03*
G54D10*
X17717Y19685D03*
X159449D03*
G54D17*
X56418Y46949D03*
G54D14*
X32205Y38484D03*
Y55414D03*
X51103Y38484D03*
Y55414D03*
%LPC*%
G75*
G54D18*
G01X-149983Y-76117D02*
Y-156117D01*
G01D02*
X864117D01*
G01X-153983Y-60117D02*
G02I-12000J0D01*
G01X-159133D02*
G02I-6850J0D01*
G01X-165983Y-76117D02*
Y-44117D01*
G01X-149983Y-60117D02*
X-181983D01*
G01X-149983Y-76117D02*
X864117D01*
G01X-149983Y-111617D02*
X864117D01*
G01X76617Y-76117D02*
Y-156117D01*
G01X214117Y-76117D02*
Y-156117D01*
G01X329117Y-76117D02*
Y-156117D01*
G01X496617Y-76117D02*
Y-156117D01*
G01X666617Y-76117D02*
Y-156117D01*
G01X864117Y-76117D02*
Y-156117D01*
G01X892117Y-60117D02*
G02I-12000J0D01*
G01X886967D02*
G02I-6850J0D01*
G01X880117Y-76117D02*
Y-44117D01*
G01X896117Y-60117D02*
X864117D01*
G54D19*
G01X-137600Y-128617D02*
Y-146117D01*
X-128866D01*
G01X-113987Y-136784D02*
X-113113Y-135909D01*
X-112458Y-134451D01*
X-112021Y-132408D01*
X-112458Y-130659D01*
X-113331Y-129492D01*
X-114860Y-128617D01*
X-120755D01*
Y-146117D01*
X-113550D01*
X-112021Y-144951D01*
X-111148Y-143200D01*
X-110711Y-141159D01*
X-111148Y-139117D01*
X-112458Y-137367D01*
X-113987Y-136784D01*
X-120755D01*
G01X-93430Y-130076D02*
X-94740Y-129200D01*
X-96268Y-128617D01*
X-98015D01*
X-99980Y-129492D01*
X-101508Y-130950D01*
X-102600Y-132701D01*
X-103473Y-135617D01*
X-103692Y-138242D01*
X-103255Y-140867D01*
X-102600Y-142617D01*
X-101290Y-144367D01*
X-99761Y-145534D01*
X-98233Y-146117D01*
X-96705D01*
X-95176Y-145534D01*
X-93866Y-144659D01*
X-92774Y-143493D01*
G01X-67600Y-128617D02*
Y-146117D01*
X-58866D01*
G01X-41366D02*
X-50100D01*
Y-128617D01*
X-41366D01*
G01X-44860Y-137075D02*
X-50100D01*
G01X-33036Y-146117D02*
Y-128617D01*
X-28670D01*
X-26923Y-129492D01*
X-25613Y-130659D01*
X-24521Y-132408D01*
X-23648Y-134451D01*
X-23430Y-137367D01*
X-23648Y-140284D01*
X-24521Y-142326D01*
X-25613Y-144076D01*
X-26923Y-145242D01*
X-28670Y-146117D01*
X-33036D01*
G01X10260Y-135909D02*
X8732Y-134742D01*
X7422Y-134451D01*
X5675Y-135034D01*
X4365Y-136200D01*
X3492Y-138242D01*
X3273Y-140284D01*
X3492Y-142326D01*
X4365Y-144076D01*
X5675Y-145534D01*
X7422Y-146117D01*
X8950Y-145534D01*
X10260Y-144367D01*
G01X28197Y-146117D02*
Y-134451D01*
G01Y-136492D02*
X27324Y-135326D01*
X26013Y-134742D01*
X24485Y-134451D01*
X22957Y-135034D01*
X21647Y-136200D01*
X20773Y-137950D01*
X20337Y-140284D01*
X20773Y-142617D01*
X21647Y-144367D01*
X22957Y-145534D01*
X24485Y-146117D01*
X26013Y-145825D01*
X27324Y-144951D01*
X28197Y-143784D01*
G01X38710Y-146117D02*
Y-134451D01*
G01Y-136784D02*
X39802Y-135617D01*
X40894Y-134742D01*
X42422Y-134451D01*
X43513Y-134742D01*
X44824Y-135617D01*
G01X63197Y-128617D02*
Y-146117D01*
G01Y-143493D02*
X62324Y-144951D01*
X61013Y-145825D01*
X59485Y-146117D01*
X57739Y-145534D01*
X56429Y-144076D01*
X55555Y-142326D01*
X55337Y-140284D01*
X55555Y-138242D01*
X56429Y-136492D01*
X57739Y-135034D01*
X59485Y-134451D01*
X61013Y-134742D01*
X62105Y-135326D01*
X63197Y-136492D01*
G01X-77660Y-101117D02*
Y-83617D01*
X-71983Y-98200D01*
X-66306Y-83617D01*
Y-101117D01*
G01X-54483D02*
X-55793Y-100825D01*
X-57103Y-99659D01*
X-57977Y-97617D01*
X-58413Y-95284D01*
X-57977Y-92950D01*
X-57103Y-90909D01*
X-55793Y-89742D01*
X-54483Y-89451D01*
X-53173Y-89742D01*
X-51863Y-90909D01*
X-50990Y-92950D01*
X-50771Y-95284D01*
X-50990Y-97617D01*
X-51863Y-99659D01*
X-53173Y-100825D01*
X-54483Y-101117D01*
G01X-33053Y-83617D02*
Y-101117D01*
G01Y-98493D02*
X-33926Y-99951D01*
X-35237Y-100825D01*
X-36765Y-101117D01*
X-38511Y-100534D01*
X-39821Y-99076D01*
X-40695Y-97326D01*
X-40913Y-95284D01*
X-40695Y-93242D01*
X-39821Y-91492D01*
X-38511Y-90034D01*
X-36765Y-89451D01*
X-35237Y-89742D01*
X-34145Y-90326D01*
X-33053Y-91492D01*
G01X-22758Y-93242D02*
X-15771D01*
X-16426Y-91200D01*
X-17518Y-90034D01*
X-19046Y-89451D01*
X-20575Y-89742D01*
X-21885Y-90617D01*
X-22758Y-92659D01*
X-23195Y-94409D01*
Y-96159D01*
X-22758Y-97909D01*
X-21666Y-99659D01*
X-20356Y-100825D01*
X-18828Y-101117D01*
X-17300Y-100534D01*
X-15771Y-98784D01*
G01X-1983Y-101117D02*
Y-83617D01*
G01X110317Y-146117D02*
Y-128617D01*
X107697Y-132117D01*
G01Y-146117D02*
X112937D01*
G01X123669Y-138826D02*
X125197Y-136784D01*
X126507Y-135617D01*
X128254Y-135034D01*
X129782Y-135617D01*
X130874Y-136784D01*
X131747Y-138534D01*
X131965Y-140575D01*
X131747Y-142326D01*
X130874Y-144076D01*
X129563Y-145534D01*
X128035Y-146117D01*
X126289Y-145534D01*
X124760Y-143784D01*
X123887Y-141159D01*
X123669Y-138242D01*
X124105Y-134451D01*
X124760Y-132408D01*
X125852Y-130367D01*
X127380Y-128909D01*
X128909Y-128617D01*
X130437Y-129200D01*
X131529Y-130659D01*
G01X140514Y-142617D02*
X141823Y-144659D01*
X143570Y-145825D01*
X145535Y-146117D01*
X147282Y-145825D01*
X149029Y-144367D01*
X150120Y-142617D01*
X150339Y-140867D01*
X149902Y-138826D01*
X148374Y-137367D01*
X146845Y-136784D01*
X144880D01*
G01X146845D02*
X148155Y-135909D01*
X149247Y-134451D01*
X149684Y-132701D01*
X149247Y-130950D01*
X148155Y-129492D01*
X146190Y-128617D01*
X144225Y-128909D01*
X142260Y-130076D01*
G01X158669Y-138826D02*
X160197Y-136784D01*
X161507Y-135617D01*
X163254Y-135034D01*
X164782Y-135617D01*
X165874Y-136784D01*
X166747Y-138534D01*
X166965Y-140575D01*
X166747Y-142326D01*
X165874Y-144076D01*
X164563Y-145534D01*
X163035Y-146117D01*
X161289Y-145534D01*
X159760Y-143784D01*
X158887Y-141159D01*
X158669Y-138242D01*
X159105Y-134451D01*
X159760Y-132408D01*
X160852Y-130367D01*
X162380Y-128909D01*
X163909Y-128617D01*
X165437Y-129200D01*
X166529Y-130659D01*
G01X180317Y-146117D02*
X181845Y-145825D01*
X183592Y-144951D01*
X184684Y-143493D01*
X185120Y-141450D01*
X184684Y-139409D01*
X183374Y-137659D01*
X181409Y-136784D01*
X179225D01*
X177915Y-136200D01*
X176823Y-134742D01*
X176387Y-132701D01*
X177042Y-130659D01*
X178570Y-129200D01*
X180317Y-128617D01*
X182063Y-129200D01*
X183592Y-130659D01*
X184247Y-132701D01*
X183810Y-134742D01*
X182719Y-136200D01*
X181409Y-136784D01*
X179225D01*
X177260Y-137659D01*
X175950Y-139409D01*
X175514Y-141450D01*
X175950Y-143493D01*
X177042Y-144951D01*
X178789Y-145825D01*
X180317Y-146117D01*
G01X97200Y-101117D02*
Y-83617D01*
X102440D01*
X104187Y-84492D01*
X105497Y-86534D01*
X105934Y-88867D01*
X105497Y-91200D01*
X104405Y-92950D01*
X102440Y-93826D01*
X97200D01*
G01X123870Y-85076D02*
X122560Y-84200D01*
X121032Y-83617D01*
X119285D01*
X117320Y-84492D01*
X115792Y-85950D01*
X114700Y-87701D01*
X113827Y-90617D01*
X113608Y-93242D01*
X114045Y-95867D01*
X114700Y-97617D01*
X116010Y-99367D01*
X117539Y-100534D01*
X119067Y-101117D01*
X120595D01*
X122124Y-100534D01*
X123434Y-99659D01*
X124526Y-98493D01*
G01X138313Y-91784D02*
X139187Y-90909D01*
X139842Y-89451D01*
X140279Y-87408D01*
X139842Y-85659D01*
X138969Y-84492D01*
X137440Y-83617D01*
X131545D01*
Y-101117D01*
X138750D01*
X140279Y-99951D01*
X141152Y-98200D01*
X141589Y-96159D01*
X141152Y-94117D01*
X139842Y-92367D01*
X138313Y-91784D01*
X131545D01*
G01X147517Y-106950D02*
X160617D01*
G01X166545Y-101117D02*
Y-83617D01*
X176589Y-101117D01*
Y-83617D01*
G01X189067Y-101117D02*
X187320Y-100825D01*
X185792Y-99659D01*
X184482Y-97909D01*
X183608Y-95867D01*
X183172Y-93534D01*
Y-91200D01*
X183608Y-88867D01*
X184482Y-86825D01*
X185792Y-85076D01*
X187320Y-83909D01*
X189067Y-83617D01*
X190813Y-83909D01*
X192342Y-85076D01*
X193652Y-86825D01*
X194526Y-88867D01*
X194962Y-91200D01*
Y-93534D01*
X194526Y-95867D01*
X193652Y-97909D01*
X192342Y-99659D01*
X190813Y-100825D01*
X189067Y-101117D01*
G01X258282Y-143784D02*
X260029Y-145242D01*
X261994Y-146117D01*
X263740D01*
X265487Y-145242D01*
X266797Y-143784D01*
X267452Y-141742D01*
X267015Y-139701D01*
X265924Y-137950D01*
X263959Y-136784D01*
X261339Y-136200D01*
X259810Y-135034D01*
X259155Y-132992D01*
X259592Y-130950D01*
X260684Y-129492D01*
X262212Y-128617D01*
X263740D01*
X265269Y-129200D01*
X266579Y-130659D01*
G01X282113Y-136784D02*
X282987Y-135909D01*
X283642Y-134451D01*
X284079Y-132408D01*
X283642Y-130659D01*
X282769Y-129492D01*
X281240Y-128617D01*
X275345D01*
Y-146117D01*
X282550D01*
X284079Y-144951D01*
X284952Y-143200D01*
X285389Y-141159D01*
X284952Y-139117D01*
X283642Y-137367D01*
X282113Y-136784D01*
X275345D01*
G01X239908Y-83617D02*
X245367Y-101117D01*
X250826Y-83617D01*
G01X267234Y-101117D02*
X258500D01*
Y-83617D01*
X267234D01*
G01X263740Y-92075D02*
X258500D01*
G01X276000Y-101117D02*
Y-83617D01*
X281459D01*
X283205Y-84492D01*
X284297Y-85659D01*
X284734Y-87992D01*
X284297Y-90326D01*
X282987Y-91784D01*
X281459Y-92659D01*
X276000D01*
G01X281459D02*
X284734Y-101117D01*
G01X297867Y-101700D02*
X297430Y-101409D01*
Y-100825D01*
X297867Y-100534D01*
X298304Y-100825D01*
Y-101409D01*
X297867Y-101700D01*
G01X452184Y-128617D02*
Y-146117D01*
X443450D01*
G01X435120Y-143493D02*
X433811Y-144951D01*
X432282Y-145825D01*
X430317Y-146117D01*
X428352Y-145534D01*
X426824Y-144367D01*
X425732Y-142326D01*
X425514Y-139992D01*
X425950Y-137659D01*
X427042Y-136200D01*
X428571Y-135034D01*
X430099Y-134742D01*
X431627Y-135034D01*
X433592Y-136200D01*
X432937Y-128617D01*
X427042D01*
G01X411507Y-137367D02*
X407140D01*
Y-142617D01*
X408450Y-144367D01*
X409979Y-145534D01*
X412162Y-146117D01*
X414345Y-145534D01*
X415874Y-144367D01*
X417184Y-142617D01*
X418057Y-140575D01*
X418494Y-138242D01*
Y-136200D01*
X418057Y-134451D01*
X417184Y-132408D01*
X415874Y-130659D01*
X414564Y-129492D01*
X412817Y-128617D01*
X411289D01*
X409542Y-129200D01*
X408232Y-130367D01*
G01X400339Y-146117D02*
Y-128617D01*
X390295Y-146117D01*
Y-128617D01*
G01X382620Y-146117D02*
Y-128617D01*
X378254D01*
X376507Y-129492D01*
X375197Y-130659D01*
X374105Y-132408D01*
X373232Y-134451D01*
X373014Y-137367D01*
X373232Y-140284D01*
X374105Y-142326D01*
X375197Y-144076D01*
X376507Y-145242D01*
X378254Y-146117D01*
X382620D01*
G01X373450Y-83617D02*
Y-101117D01*
X382184D01*
G01X399247D02*
Y-89451D01*
G01Y-91492D02*
X398374Y-90326D01*
X397063Y-89742D01*
X395535Y-89451D01*
X394007Y-90034D01*
X392697Y-91200D01*
X391823Y-92950D01*
X391387Y-95284D01*
X391823Y-97617D01*
X392697Y-99367D01*
X394007Y-100534D01*
X395535Y-101117D01*
X397063Y-100825D01*
X398374Y-99951D01*
X399247Y-98784D01*
G01X408232Y-106367D02*
X409542Y-106950D01*
X411289Y-106367D01*
X412380Y-105201D01*
X413254Y-103742D01*
X414563Y-99076D01*
X417402Y-89451D01*
G01X410415D02*
X414563Y-99076D01*
G01X427042Y-93242D02*
X434029D01*
X433374Y-91200D01*
X432282Y-90034D01*
X430754Y-89451D01*
X429225Y-89742D01*
X427915Y-90617D01*
X427042Y-92659D01*
X426605Y-94409D01*
Y-96159D01*
X427042Y-97909D01*
X428134Y-99659D01*
X429444Y-100825D01*
X430972Y-101117D01*
X432500Y-100534D01*
X434029Y-98784D01*
G01X444760Y-101117D02*
Y-89451D01*
G01Y-91784D02*
X445852Y-90617D01*
X446944Y-89742D01*
X448472Y-89451D01*
X449563Y-89742D01*
X450874Y-90617D01*
G01X515564Y-101117D02*
Y-83617D01*
X519930D01*
X521677Y-84492D01*
X522987Y-85659D01*
X524079Y-87408D01*
X524952Y-89451D01*
X525170Y-92367D01*
X524952Y-95284D01*
X524079Y-97326D01*
X522987Y-99076D01*
X521677Y-100242D01*
X519930Y-101117D01*
X515564D01*
G01X534592Y-93242D02*
X541579D01*
X540924Y-91200D01*
X539832Y-90034D01*
X538304Y-89451D01*
X536775Y-89742D01*
X535465Y-90617D01*
X534592Y-92659D01*
X534155Y-94409D01*
Y-96159D01*
X534592Y-97909D01*
X535684Y-99659D01*
X536994Y-100825D01*
X538522Y-101117D01*
X540050Y-100534D01*
X541579Y-98784D01*
G01X552092Y-99076D02*
X553184Y-100242D01*
X554712Y-101117D01*
X556022D01*
X557332Y-100534D01*
X558205Y-99659D01*
X558642Y-98493D01*
X558424Y-96742D01*
X557550Y-95867D01*
X553620Y-94117D01*
X552747Y-92075D01*
X553184Y-90617D01*
X554057Y-89742D01*
X555367Y-89451D01*
X556677Y-89742D01*
X557987Y-90617D01*
G01X572867Y-89451D02*
Y-101117D01*
G01Y-84784D02*
X572430Y-84492D01*
Y-83909D01*
X572867Y-83617D01*
X573304Y-83909D01*
Y-84492D01*
X572867Y-84784D01*
G01X587310Y-105492D02*
X588839Y-106659D01*
X590585Y-106950D01*
X592113Y-106659D01*
X593424Y-105201D01*
X594297Y-103159D01*
Y-89451D01*
G01Y-91784D02*
X593424Y-90617D01*
X592113Y-89742D01*
X590585Y-89451D01*
X588839Y-90034D01*
X587747Y-91200D01*
X586873Y-93242D01*
X586437Y-95284D01*
X586655Y-97034D01*
X587529Y-99076D01*
X588839Y-100534D01*
X590585Y-101117D01*
X591895Y-100825D01*
X593424Y-99659D01*
X594297Y-98493D01*
G01X604155Y-101117D02*
Y-89451D01*
G01Y-92367D02*
X605029Y-90909D01*
X606339Y-89742D01*
X608085Y-89451D01*
X609613Y-89742D01*
X610924Y-90909D01*
X611579Y-92950D01*
Y-101117D01*
G01X622092Y-93242D02*
X629079D01*
X628424Y-91200D01*
X627332Y-90034D01*
X625804Y-89451D01*
X624275Y-89742D01*
X622965Y-90617D01*
X622092Y-92659D01*
X621655Y-94409D01*
Y-96159D01*
X622092Y-97909D01*
X623184Y-99659D01*
X624494Y-100825D01*
X626022Y-101117D01*
X627550Y-100534D01*
X629079Y-98784D01*
G01X639810Y-101117D02*
Y-89451D01*
G01Y-91784D02*
X640902Y-90617D01*
X641994Y-89742D01*
X643522Y-89451D01*
X644613Y-89742D01*
X645924Y-90617D01*
G01X559969Y-128617D02*
X568265D01*
X559969Y-146117D01*
X568265D01*
G01X581617D02*
X579870Y-145825D01*
X578342Y-144659D01*
X577032Y-142909D01*
X576158Y-140867D01*
X575722Y-138534D01*
Y-136200D01*
X576158Y-133867D01*
X577032Y-131825D01*
X578342Y-130076D01*
X579870Y-128909D01*
X581617Y-128617D01*
X583363Y-128909D01*
X584892Y-130076D01*
X586202Y-131825D01*
X587076Y-133867D01*
X587512Y-136200D01*
Y-138534D01*
X587076Y-140867D01*
X586202Y-142909D01*
X584892Y-144659D01*
X583363Y-145825D01*
X581617Y-146117D01*
G01X603484D02*
X594750D01*
Y-128617D01*
X603484D01*
G01X599990Y-137075D02*
X594750D01*
G01X686567Y-128617D02*
X684820Y-129200D01*
X683510Y-130659D01*
X682637Y-132408D01*
X681982Y-134742D01*
X681764Y-137367D01*
X681982Y-139992D01*
X682637Y-142326D01*
X683510Y-144076D01*
X684820Y-145534D01*
X686567Y-146117D01*
X688313Y-145534D01*
X689624Y-144076D01*
X690497Y-142326D01*
X691152Y-139992D01*
X691370Y-137367D01*
X691152Y-134742D01*
X690497Y-132408D01*
X689624Y-130659D01*
X688313Y-129200D01*
X686567Y-128617D01*
G01X699919Y-131534D02*
X701229Y-129784D01*
X702757Y-128909D01*
X704504Y-128617D01*
X706687Y-129200D01*
X708215Y-130659D01*
X708652Y-132408D01*
X708434Y-134159D01*
X707560Y-135617D01*
X703194Y-138534D01*
X701229Y-140575D01*
X699919Y-143493D01*
X699482Y-146117D01*
X708652D01*
G01X717637Y-146700D02*
X725497Y-128617D01*
G01X739067D02*
X737320Y-129200D01*
X736010Y-130659D01*
X735137Y-132408D01*
X734482Y-134742D01*
X734264Y-137367D01*
X734482Y-139992D01*
X735137Y-142326D01*
X736010Y-144076D01*
X737320Y-145534D01*
X739067Y-146117D01*
X740813Y-145534D01*
X742124Y-144076D01*
X742997Y-142326D01*
X743652Y-139992D01*
X743870Y-137367D01*
X743652Y-134742D01*
X742997Y-132408D01*
X742124Y-130659D01*
X740813Y-129200D01*
X739067Y-128617D01*
G01X756130Y-146117D02*
X756567Y-142326D01*
X757222Y-139117D01*
X758095Y-136200D01*
X759187Y-132992D01*
X760934Y-128617D01*
X752200D01*
G01X770137Y-146700D02*
X777997Y-128617D01*
G01X787419Y-131534D02*
X788729Y-129784D01*
X790257Y-128909D01*
X792004Y-128617D01*
X794187Y-129200D01*
X795715Y-130659D01*
X796152Y-132408D01*
X795934Y-134159D01*
X795060Y-135617D01*
X790694Y-138534D01*
X788729Y-140575D01*
X787419Y-143493D01*
X786982Y-146117D01*
X796152D01*
G01X809067Y-128617D02*
X807320Y-129200D01*
X806010Y-130659D01*
X805137Y-132408D01*
X804482Y-134742D01*
X804264Y-137367D01*
X804482Y-139992D01*
X805137Y-142326D01*
X806010Y-144076D01*
X807320Y-145534D01*
X809067Y-146117D01*
X810813Y-145534D01*
X812124Y-144076D01*
X812997Y-142326D01*
X813652Y-139992D01*
X813870Y-137367D01*
X813652Y-134742D01*
X812997Y-132408D01*
X812124Y-130659D01*
X810813Y-129200D01*
X809067Y-128617D01*
G01X826567Y-146117D02*
Y-128617D01*
X823947Y-132117D01*
G01Y-146117D02*
X829187D01*
G01X843630D02*
X844067Y-142326D01*
X844722Y-139117D01*
X845595Y-136200D01*
X846687Y-132992D01*
X848434Y-128617D01*
X839700D01*
G01X734264Y-101117D02*
Y-83617D01*
X738630D01*
X740377Y-84492D01*
X741687Y-85659D01*
X742779Y-87408D01*
X743652Y-89451D01*
X743870Y-92367D01*
X743652Y-95284D01*
X742779Y-97326D01*
X741687Y-99076D01*
X740377Y-100242D01*
X738630Y-101117D01*
X734264D01*
G01X760497D02*
Y-89451D01*
G01Y-91492D02*
X759624Y-90326D01*
X758313Y-89742D01*
X756785Y-89451D01*
X755257Y-90034D01*
X753947Y-91200D01*
X753073Y-92950D01*
X752637Y-95284D01*
X753073Y-97617D01*
X753947Y-99367D01*
X755257Y-100534D01*
X756785Y-101117D01*
X758313Y-100825D01*
X759624Y-99951D01*
X760497Y-98784D01*
G01X774067Y-83617D02*
Y-101117D01*
G01X771010Y-89451D02*
X777124D01*
G01X788292Y-93242D02*
X795279D01*
X794624Y-91200D01*
X793532Y-90034D01*
X792004Y-89451D01*
X790475Y-89742D01*
X789165Y-90617D01*
X788292Y-92659D01*
X787855Y-94409D01*
Y-96159D01*
X788292Y-97909D01*
X789384Y-99659D01*
X790694Y-100825D01*
X792222Y-101117D01*
X793750Y-100534D01*
X795279Y-98784D01*
M02*
